(kicad_pcb
	(version 20260206)
	(generator "pcbnew")
	(generator_version "10.0")
	(general
		(thickness 1.6)
		(legacy_teardrops no)
	)
	(paper "A4")
	(title_block
		(title "Bryce Canyon_IOM_M2_16342-2_OCP.brd")
		(comment 1 "Bryce Canyon / footprints 727-733 of 1146")
	)
	(layers
		(0 "F.Cu" signal "TOP")
		(4 "In1.Cu" signal "L2GND")
		(6 "In2.Cu" signal "L3")
		(8 "In3.Cu" signal "L4VCC")
		(10 "In4.Cu" signal "L5VCC")
		(12 "In5.Cu" signal "L6")
		(14 "In6.Cu" signal "L7GND")
		(2 "B.Cu" signal "BOTTOM")
		(9 "F.Adhes" user "F.Adhesive")
		(11 "B.Adhes" user "B.Adhesive")
		(13 "F.Paste" user "Package Geometry/Pastemask Top")
		(15 "B.Paste" user "Package Geometry/Pastemask Bottom")
		(5 "F.SilkS" user "Ref Des/Silkscreen Top")
		(7 "B.SilkS" user "Ref Des/Silkscreen Bottom")
		(1 "F.Mask" user "Board Geometry/Soldermask Top")
		(3 "B.Mask" user "Board Geometry/Soldermask Bottom")
		(17 "Dwgs.User" user "User.Drawings")
		(19 "Cmts.User" user "User.Comments")
		(21 "Eco1.User" user "User.Eco1")
		(23 "Eco2.User" user "User.Eco2")
		(25 "Edge.Cuts" user "Board Geometry/Outline")
		(27 "Margin" user)
		(31 "F.CrtYd" user "Package Geometry/Place Bound Top")
		(29 "B.CrtYd" user "Package Geometry/Place Bound Bottom")
		(35 "F.Fab" user "Ref Des/Assembly Top")
		(33 "B.Fab" user "Ref Des/Assembly Bottom")
	)
	(footprint ""
		(layer "B.Cu")
		(at 166.585138 -9.171178)
		(property "Reference" "C218"
			(at 0 0 0)
			(layer "B.SilkS")
			(hide yes)
			(effects
				(font
					(size 1.27 1.27)
				)
				(justify mirror)
			)
		)
		(property "Value" "SC10U6D3V5KX-4GP"
			(at 0.0762 -6.1214 0)
			(unlocked yes)
			(layer "B.Fab")
			(hide yes)
			(effects
				(font
					(size 1.016 1.016)
					(thickness 0.1524)
				)
				(justify mirror)
			)
		)
		(property "Device Type" "C805H58"
			(at 0.0762 -8.1534 0)
			(unlocked yes)
			(layer "B.Fab")
			(hide yes)
			(effects
				(font
					(size 1.016 1.016)
					(thickness 0.1524)
				)
				(justify mirror)
			)
		)
		(duplicate_pad_numbers_are_jumpers no)
		(fp_line
			(start -0.635 0)
			(end 0.635 0)
			(stroke
				(width 0.508)
				(type default)
			)
			(layer "B.SilkS")
		)
		(fp_rect
			(start 0.9652 1.778)
			(end -0.9652 -1.778)
			(stroke
				(width 0)
				(type default)
			)
			(fill no)
			(layer "B.CrtYd")
		)
		(fp_poly
			(pts
				(xy 0.9652 -1.778) (xy -0.9652 -1.778) (xy -0.9652 1.778) (xy 0.9652 1.778)
			)
			(stroke
				(width 0)
				(type default)
			)
			(fill no)
			(layer "B.Fab")
		)
		(pad "1" smd rect
			(at 0 -0.9652 180)
			(size 1.397 1.143)
			(layers "B.Cu" "B.Mask" "B.Paste")
			(net "P1V8_STBY")
		)
		(pad "2" smd rect
			(at 0 0.9652 180)
			(size 1.397 1.143)
			(layers "B.Cu" "B.Mask" "B.Paste")
			(net "GND")
		)
	)
	(footprint ""
		(layer "B.Cu")
		(at 22.014942 -129.1082 180)
		(property "Reference" "R260"
			(at 0 0 0)
			(layer "B.SilkS")
			(hide yes)
			(effects
				(font
					(size 1.27 1.27)
				)
				(justify mirror)
			)
		)
		(property "Value" "120R2F-GP"
			(at -0.064008 -3.993896 180)
			(unlocked yes)
			(layer "B.Fab")
			(hide yes)
			(effects
				(font
					(size 1.016 1.016)
					(thickness 0.1524)
				)
				(justify mirror)
			)
		)
		(property "Device Type" "R402H16"
			(at -0.064008 -5.517896 180)
			(unlocked yes)
			(layer "B.Fab")
			(hide yes)
			(effects
				(font
					(size 1.016 1.016)
					(thickness 0.1524)
				)
				(justify mirror)
			)
		)
		(duplicate_pad_numbers_are_jumpers no)
		(fp_line
			(start 0.508 -0.9398)
			(end 0.508 0.9398)
			(stroke
				(width 0.1524)
				(type default)
			)
			(layer "B.SilkS")
		)
		(fp_line
			(start -0.508 -0.9398)
			(end 0.508 -0.9398)
			(stroke
				(width 0.1524)
				(type default)
			)
			(layer "B.SilkS")
		)
		(fp_rect
			(start 0.508 0.9398)
			(end -0.508 -0.9398)
			(stroke
				(width 0)
				(type default)
			)
			(fill no)
			(layer "B.CrtYd")
		)
		(fp_rect
			(start 0.508 0.9398)
			(end -0.508 -0.9398)
			(stroke
				(width 0)
				(type default)
			)
			(fill no)
			(layer "B.Fab")
		)
		(pad "1" smd custom
			(at 0 -0.4445)
			(size 0.1397 0.1397)
			(layers "B.Cu" "B.Mask" "B.Paste")
			(net "GND")
			(options
				(clearance outline)
				(anchor circle)
			)
			(primitives
				(gr_poly
					(pts
						(arc
							(start -0.1778 0.2794)
							(mid -0.249642 0.249642)
							(end -0.2794 0.1778)
						)
						(arc
							(start -0.2794 -0.1778)
							(mid -0.249642 -0.249642)
							(end -0.1778 -0.2794)
						)
						(arc
							(start 0.1778 -0.2794)
							(mid 0.249642 -0.249642)
							(end 0.2794 -0.1778)
						)
						(arc
							(start 0.2794 0.1778)
							(mid 0.249642 0.249642)
							(end 0.1778 0.2794)
						)
					)
					(width 0)
					(fill yes)
				)
			)
		)
		(pad "2" smd custom
			(at 0 0.4445)
			(size 0.1397 0.1397)
			(layers "B.Cu" "B.Mask" "B.Paste")
			(net "MEMA_13")
			(options
				(clearance outline)
				(anchor circle)
			)
			(primitives
				(gr_poly
					(pts
						(arc
							(start -0.1778 0.2794)
							(mid -0.249642 0.249642)
							(end -0.2794 0.1778)
						)
						(arc
							(start -0.2794 -0.1778)
							(mid -0.249642 -0.249642)
							(end -0.1778 -0.2794)
						)
						(arc
							(start 0.1778 -0.2794)
							(mid 0.249642 -0.249642)
							(end 0.2794 -0.1778)
						)
						(arc
							(start 0.2794 0.1778)
							(mid 0.249642 0.249642)
							(end 0.1778 0.2794)
						)
					)
					(width 0)
					(fill yes)
				)
			)
		)
	)
	(footprint ""
		(layer "B.Cu")
		(at 10.20191 -135.290052 90)
		(property "Reference" "R256"
			(at 0 0 90)
			(layer "B.SilkS")
			(hide yes)
			(effects
				(font
					(size 1.27 1.27)
				)
				(justify mirror)
			)
		)
		(property "Value" "120R2F-GP"
			(at -0.064008 -3.993896 90)
			(unlocked yes)
			(layer "B.Fab")
			(hide yes)
			(effects
				(font
					(size 1.016 1.016)
					(thickness 0.1524)
				)
				(justify mirror)
			)
		)
		(property "Device Type" "R402H16"
			(at -0.064008 -5.517896 90)
			(unlocked yes)
			(layer "B.Fab")
			(hide yes)
			(effects
				(font
					(size 1.016 1.016)
					(thickness 0.1524)
				)
				(justify mirror)
			)
		)
		(duplicate_pad_numbers_are_jumpers no)
		(fp_line
			(start 0.508 -0.9398)
			(end 0.508 0.9398)
			(stroke
				(width 0.1524)
				(type default)
			)
			(layer "B.SilkS")
		)
		(fp_line
			(start -0.508 -0.9398)
			(end 0.508 -0.9398)
			(stroke
				(width 0.1524)
				(type default)
			)
			(layer "B.SilkS")
		)
		(fp_rect
			(start 0.508 0.9398)
			(end -0.508 -0.9398)
			(stroke
				(width 0)
				(type default)
			)
			(fill no)
			(layer "B.CrtYd")
		)
		(fp_rect
			(start 0.508 0.9398)
			(end -0.508 -0.9398)
			(stroke
				(width 0)
				(type default)
			)
			(fill no)
			(layer "B.Fab")
		)
		(pad "1" smd custom
			(at 0 -0.4445 270)
			(size 0.1397 0.1397)
			(layers "B.Cu" "B.Mask" "B.Paste")
			(net "GND")
			(options
				(clearance outline)
				(anchor circle)
			)
			(primitives
				(gr_poly
					(pts
						(arc
							(start -0.1778 0.2794)
							(mid -0.249642 0.249642)
							(end -0.2794 0.1778)
						)
						(arc
							(start -0.2794 -0.1778)
							(mid -0.249642 -0.249642)
							(end -0.1778 -0.2794)
						)
						(arc
							(start 0.1778 -0.2794)
							(mid 0.249642 -0.249642)
							(end 0.2794 -0.1778)
						)
						(arc
							(start 0.2794 0.1778)
							(mid 0.249642 0.249642)
							(end 0.1778 0.2794)
						)
					)
					(width 0)
					(fill yes)
				)
			)
		)
		(pad "2" smd custom
			(at 0 0.4445 270)
			(size 0.1397 0.1397)
			(layers "B.Cu" "B.Mask" "B.Paste")
			(net "MEMA_11")
			(options
				(clearance outline)
				(anchor circle)
			)
			(primitives
				(gr_poly
					(pts
						(arc
							(start -0.1778 0.2794)
							(mid -0.249642 0.249642)
							(end -0.2794 0.1778)
						)
						(arc
							(start -0.2794 -0.1778)
							(mid -0.249642 -0.249642)
							(end -0.1778 -0.2794)
						)
						(arc
							(start 0.1778 -0.2794)
							(mid 0.249642 -0.249642)
							(end 0.2794 -0.1778)
						)
						(arc
							(start 0.2794 0.1778)
							(mid 0.249642 0.249642)
							(end 0.1778 0.2794)
						)
					)
					(width 0)
					(fill yes)
				)
			)
		)
	)
	(footprint ""
		(layer "B.Cu")
		(at 55.0164 -127.24892)
		(property "Reference" "U37"
			(at 0 0 0)
			(layer "B.SilkS")
			(hide yes)
			(effects
				(font
					(size 1.27 1.27)
				)
				(justify mirror)
			)
		)
		(property "Value" "SN74LVC1G08DCKR-GP"
			(at 2.3368 -8.6868 0)
			(unlocked yes)
			(layer "B.Fab")
			(hide yes)
			(effects
				(font
					(size 1.016 1.016)
					(thickness 0.1524)
				)
				(justify mirror)
			)
		)
		(property "Device Type" "SC70-5H44"
			(at 2.3114 -10.414 0)
			(unlocked yes)
			(layer "B.Fab")
			(hide yes)
			(effects
				(font
					(size 1.016 1.016)
					(thickness 0.1524)
				)
				(justify mirror)
			)
		)
		(duplicate_pad_numbers_are_jumpers no)
		(fp_line
			(start -1.3843 -1.8034)
			(end -1.3843 -1.1176)
			(stroke
				(width 0.3302)
				(type default)
			)
			(layer "B.SilkS")
		)
		(fp_line
			(start -1.27 -1.7018)
			(end -1.27 1.7018)
			(stroke
				(width 0.1524)
				(type default)
			)
			(layer "B.SilkS")
		)
		(fp_line
			(start -1.27 1.7018)
			(end 1.27 1.7018)
			(stroke
				(width 0.1524)
				(type default)
			)
			(layer "B.SilkS")
		)
		(fp_line
			(start -0.6604 -1.8034)
			(end -1.3843 -1.8034)
			(stroke
				(width 0.3302)
				(type default)
			)
			(layer "B.SilkS")
		)
		(fp_line
			(start 1.27 -1.7018)
			(end -1.27 -1.7018)
			(stroke
				(width 0.1524)
				(type default)
			)
			(layer "B.SilkS")
		)
		(fp_line
			(start 1.27 1.7018)
			(end 1.27 -1.7018)
			(stroke
				(width 0.1524)
				(type default)
			)
			(layer "B.SilkS")
		)
		(fp_rect
			(start 1.524 1.9558)
			(end -1.524 -1.9558)
			(stroke
				(width 0)
				(type default)
			)
			(fill no)
			(layer "B.CrtYd")
		)
		(fp_poly
			(pts
				(xy 1.524 -1.9558) (xy -1.524 -1.9558) (xy -1.524 1.9558) (xy 1.524 1.9558)
			)
			(stroke
				(width 0)
				(type default)
			)
			(fill no)
			(layer "B.Fab")
		)
		(pad "1" smd rect
			(at -0.65024 -0.8255 180)
			(size 0.4064 1.2192)
			(layers "B.Cu" "B.Mask" "B.Paste")
			(net "RST_BMC_EXTRST_N_1")
		)
		(pad "2" smd rect
			(at 0 -0.8255 180)
			(size 0.4064 1.2192)
			(layers "B.Cu" "B.Mask" "B.Paste")
			(net "DEBUG_RST_BTN_N_R")
		)
		(pad "3" smd rect
			(at 0.65024 -0.8255 180)
			(size 0.4064 1.2192)
			(layers "B.Cu" "B.Mask" "B.Paste")
			(net "GND")
		)
		(pad "4" smd rect
			(at 0.65024 0.8255 180)
			(size 0.4064 1.2192)
			(layers "B.Cu" "B.Mask" "B.Paste")
			(net "RST_BMC_EXTRST_N")
		)
		(pad "5" smd rect
			(at -0.65024 0.8255 180)
			(size 0.4064 1.2192)
			(layers "B.Cu" "B.Mask" "B.Paste")
			(net "P3V3_STBY")
		)
	)
	(footprint ""
		(layer "B.Cu")
		(at 78.109318 -173.471586 -90)
		(property "Reference" "R301"
			(at 0 0 90)
			(layer "B.SilkS")
			(hide yes)
			(effects
				(font
					(size 1.27 1.27)
				)
				(justify mirror)
			)
		)
		(property "Value" "0R2J-2-GP"
			(at -0.064008 -3.993896 270)
			(unlocked yes)
			(layer "B.Fab")
			(hide yes)
			(effects
				(font
					(size 1.016 1.016)
					(thickness 0.1524)
				)
				(justify mirror)
			)
		)
		(property "Device Type" "R402H16"
			(at -0.064008 -5.517896 270)
			(unlocked yes)
			(layer "B.Fab")
			(hide yes)
			(effects
				(font
					(size 1.016 1.016)
					(thickness 0.1524)
				)
				(justify mirror)
			)
		)
		(duplicate_pad_numbers_are_jumpers no)
		(fp_line
			(start -0.508 -0.9398)
			(end 0.508 -0.9398)
			(stroke
				(width 0.1524)
				(type default)
			)
			(layer "B.SilkS")
		)
		(fp_line
			(start 0.508 -0.9398)
			(end 0.508 0.9398)
			(stroke
				(width 0.1524)
				(type default)
			)
			(layer "B.SilkS")
		)
		(fp_rect
			(start 0.508 0.9398)
			(end -0.508 -0.9398)
			(stroke
				(width 0)
				(type default)
			)
			(fill no)
			(layer "B.CrtYd")
		)
		(fp_rect
			(start 0.508 0.9398)
			(end -0.508 -0.9398)
			(stroke
				(width 0)
				(type default)
			)
			(fill no)
			(layer "B.Fab")
		)
		(pad "1" smd custom
			(at 0 -0.4445 90)
			(size 0.1397 0.1397)
			(layers "B.Cu" "B.Mask" "B.Paste")
			(net "UART_EXP_BMC_RX")
			(options
				(clearance outline)
				(anchor circle)
			)
			(primitives
				(gr_poly
					(pts
						(arc
							(start -0.1778 0.2794)
							(mid -0.249642 0.249642)
							(end -0.2794 0.1778)
						)
						(arc
							(start -0.2794 -0.1778)
							(mid -0.249642 -0.249642)
							(end -0.1778 -0.2794)
						)
						(arc
							(start 0.1778 -0.2794)
							(mid 0.249642 -0.249642)
							(end 0.2794 -0.1778)
						)
						(arc
							(start 0.2794 0.1778)
							(mid 0.249642 0.249642)
							(end 0.1778 0.2794)
						)
					)
					(width 0)
					(fill yes)
				)
			)
		)
		(pad "2" smd custom
			(at 0 0.4445 90)
			(size 0.1397 0.1397)
			(layers "B.Cu" "B.Mask" "B.Paste")
			(net "UART_EXP_BMC_RX_R")
			(options
				(clearance outline)
				(anchor circle)
			)
			(primitives
				(gr_poly
					(pts
						(arc
							(start -0.1778 0.2794)
							(mid -0.249642 0.249642)
							(end -0.2794 0.1778)
						)
						(arc
							(start -0.2794 -0.1778)
							(mid -0.249642 -0.249642)
							(end -0.1778 -0.2794)
						)
						(arc
							(start 0.1778 -0.2794)
							(mid 0.249642 -0.249642)
							(end 0.2794 -0.1778)
						)
						(arc
							(start 0.2794 0.1778)
							(mid 0.249642 0.249642)
							(end 0.1778 0.2794)
						)
					)
					(width 0)
					(fill yes)
				)
			)
		)
	)
	(footprint ""
		(layer "B.Cu")
		(at 93.37548 -152.746456 180)
		(property "Reference" "C9"
			(at 0 0 0)
			(layer "B.SilkS")
			(hide yes)
			(effects
				(font
					(size 1.27 1.27)
				)
				(justify mirror)
			)
		)
		(property "Value" "SC1U16V2KX-7-GP"
			(at -1.7526 -1.6002 180)
			(unlocked yes)
			(layer "B.Fab")
			(hide yes)
			(effects
				(font
					(size 1.016 1.016)
					(thickness 0.1524)
				)
				(justify mirror)
			)
		)
		(property "Device Type" "C402-TO0D2H24"
			(at -1.7526 -3.1242 180)
			(unlocked yes)
			(layer "B.Fab")
			(hide yes)
			(effects
				(font
					(size 1.016 1.016)
					(thickness 0.1524)
				)
				(justify mirror)
			)
		)
		(duplicate_pad_numbers_are_jumpers no)
		(fp_rect
			(start 0.4826 0.889)
			(end -0.4826 -0.889)
			(stroke
				(width 0)
				(type default)
			)
			(fill no)
			(layer "B.CrtYd")
		)
		(fp_rect
			(start 0.4826 0.889)
			(end -0.4826 -0.889)
			(stroke
				(width 0)
				(type default)
			)
			(fill no)
			(layer "B.Fab")
		)
		(pad "1" smd custom
			(at 0 -0.4572)
			(size 0.1524 0.1524)
			(layers "B.Cu" "B.Mask" "B.Paste")
			(net "P3V3_STBY")
			(options
				(clearance outline)
				(anchor circle)
			)
			(primitives
				(gr_poly
					(pts
						(arc
							(start -0.254 -0.3048)
							(mid -0.325842 -0.275042)
							(end -0.3556 -0.2032)
						)
						(arc
							(start -0.3556 0.2032)
							(mid -0.325842 0.275042)
							(end -0.254 0.3048)
						)
						(arc
							(start 0.254 0.3048)
							(mid 0.325842 0.275042)
							(end 0.3556 0.2032)
						)
						(arc
							(start 0.3556 -0.2032)
							(mid 0.325842 -0.275042)
							(end 0.254 -0.3048)
						)
					)
					(width 0)
					(fill yes)
				)
			)
		)
		(pad "2" smd custom
			(at 0 0.4572)
			(size 0.1524 0.1524)
			(layers "B.Cu" "B.Mask" "B.Paste")
			(net "GND")
			(options
				(clearance outline)
				(anchor circle)
			)
			(primitives
				(gr_poly
					(pts
						(arc
							(start -0.254 -0.3048)
							(mid -0.325842 -0.275042)
							(end -0.3556 -0.2032)
						)
						(arc
							(start -0.3556 0.2032)
							(mid -0.325842 0.275042)
							(end -0.254 0.3048)
						)
						(arc
							(start 0.254 0.3048)
							(mid 0.325842 0.275042)
							(end 0.3556 0.2032)
						)
						(arc
							(start 0.3556 -0.2032)
							(mid 0.325842 -0.275042)
							(end 0.254 -0.3048)
						)
					)
					(width 0)
					(fill yes)
				)
			)
		)
	)
	(footprint ""
		(layer "B.Cu")
		(at 65.2526 -136.0932 -90)
		(property "Reference" "R785"
			(at 0 0 90)
			(layer "B.SilkS")
			(hide yes)
			(effects
				(font
					(size 1.27 1.27)
				)
				(justify mirror)
			)
		)
		(property "Value" "10KR2F-2-GP"
			(at -0.064008 -3.993896 270)
			(unlocked yes)
			(layer "B.Fab")
			(hide yes)
			(effects
				(font
					(size 1.016 1.016)
					(thickness 0.1524)
				)
				(justify mirror)
			)
		)
		(property "Device Type" "R402H16"
			(at -0.064008 -5.517896 270)
			(unlocked yes)
			(layer "B.Fab")
			(hide yes)
			(effects
				(font
					(size 1.016 1.016)
					(thickness 0.1524)
				)
				(justify mirror)
			)
		)
		(duplicate_pad_numbers_are_jumpers no)
		(fp_line
			(start -0.508 -0.9398)
			(end 0.508 -0.9398)
			(stroke
				(width 0.1524)
				(type default)
			)
			(layer "B.SilkS")
		)
		(fp_line
			(start 0.508 -0.9398)
			(end 0.508 0.9398)
			(stroke
				(width 0.1524)
				(type default)
			)
			(layer "B.SilkS")
		)
		(fp_rect
			(start 0.508 0.9398)
			(end -0.508 -0.9398)
			(stroke
				(width 0)
				(type default)
			)
			(fill no)
			(layer "B.CrtYd")
		)
		(fp_rect
			(start 0.508 0.9398)
			(end -0.508 -0.9398)
			(stroke
				(width 0)
				(type default)
			)
			(fill no)
			(layer "B.Fab")
		)
		(pad "1" smd custom
			(at 0 -0.4445 90)
			(size 0.1397 0.1397)
			(layers "B.Cu" "B.Mask" "B.Paste")
			(net "P3V3_STBY")
			(options
				(clearance outline)
				(anchor circle)
			)
			(primitives
				(gr_poly
					(pts
						(arc
							(start -0.1778 0.2794)
							(mid -0.249642 0.249642)
							(end -0.2794 0.1778)
						)
						(arc
							(start -0.2794 -0.1778)
							(mid -0.249642 -0.249642)
							(end -0.1778 -0.2794)
						)
						(arc
							(start 0.1778 -0.2794)
							(mid 0.249642 -0.249642)
							(end 0.2794 -0.1778)
						)
						(arc
							(start 0.2794 0.1778)
							(mid 0.249642 0.249642)
							(end 0.1778 0.2794)
						)
					)
					(width 0)
					(fill yes)
				)
			)
		)
		(pad "2" smd custom
			(at 0 0.4445 90)
			(size 0.1397 0.1397)
			(layers "B.Cu" "B.Mask" "B.Paste")
			(net "TP_BMC_GPIOA0")
			(options
				(clearance outline)
				(anchor circle)
			)
			(primitives
				(gr_poly
					(pts
						(arc
							(start -0.1778 0.2794)
							(mid -0.249642 0.249642)
							(end -0.2794 0.1778)
						)
						(arc
							(start -0.2794 -0.1778)
							(mid -0.249642 -0.249642)
							(end -0.1778 -0.2794)
						)
						(arc
							(start 0.1778 -0.2794)
							(mid 0.249642 -0.249642)
							(end 0.2794 -0.1778)
						)
						(arc
							(start 0.2794 0.1778)
							(mid 0.249642 0.249642)
							(end 0.1778 0.2794)
						)
					)
					(width 0)
					(fill yes)
				)
			)
		)
	)
)
